FILE_TYPE = CONNECTIVITY;
{Allegro Design Entry HDL 17.2-2016 S081 (4005846) 1/11/2022}
"PAGE_NUMBER" = 163;
0"NC";
1"P3V3_AUX\g";
2"P3V3_AUX\g";
3"P3V3_AUX\g";
4"P3V3_AUX\g";
5"P12V_SCM_R\g";
6"P3V3_AUX\g";
7"P3V3_M2_0\g";
8"P3V3\g";
9"P3V3\g";
10"P3V3_OCP_V3_2_R\g";
11"P3V3_OCP_V3_2\g";
12"P3V3_AUX\g";
13"P3V3_AUX\g";
14"P3V3_AUX\g";
15"P12V_SCM_R\g";
16"P12V_SCM\g";
17"P3V3_OCP_V3_2_R\g";
18"GND\g";
19"GND\g";
20"GND\g";
21"GND\g";
22"GND\g";
23"GND\g";
24"GND\g";
25"GND\g";
26"GND\g";
27"GND\g";
28"GND\g";
29"GND\g";
30"NC_INA230_4_NC0";
31"M2_0_P3V3_ADC_ALERT_R";
32"VSENSE_P12V_INA230_3_INN";
33"VSENSE_P12V_INA230_3_INP";
34"INA230_4_A1";
35"NC_INA230_3_NC5";
36"NC_INA230_3_NC4";
37"NC_INA230_3_NC3";
38"NC_INA230_3_NC2";
39"NC_INA230_3_NC1";
40"NC_INA230_3_NC0";
41"OCP_V3_2_P3V3_ADC_ALERT_R";
42"NC_INA230_4_NC3";
43"NC_INA230_4_NC4";
44"P12V_SCM_ADC_ALERT_R";
45"NC_INA230_5_NC2";
46"P12V_SCM_ADC_ALERT";
47"NC_INA230_5_NC1";
48"NC_INA230_5_NC0";
49"NC_INA230_5_NC4";
50"NC_INA230_5_NC5";
51"NC_INA230_5_NC3";
52"INA230_5_A1";
53"INA230_5_A0";
54"SMB_INA230_5_3V3AUX_SCL_R1";
55"SMB_INA230_5_3V3AUX_SDA_R1";
56"VSENSE_P12V_INA230_5_INP";
57"VSENSE_P12V_INA230_5_INN";
58"M2_0_P3V3_ADC_ALERT";
59"NC_INA230_4_NC1";
60"NC_INA230_4_NC2";
61"NC_INA230_4_NC5";
62"INA230_4_A0";
63"SMB_INA230_4_3V3AUX_SCL_R1";
64"SMB_INA230_4_3V3AUX_SDA_R1";
65"VSENSE_P12V_INA230_4_INP";
66"VSENSE_P12V_INA230_4_INN";
67"OCP_V3_2_P3V3_ADC_ALERT";
68"SMB_INA230_3_3V3AUX_SDA_R1";
69"SMB_INA230_3_3V3AUX_SCL_R1";
70"INA230_3_A0";
71"INA230_3_A1";
72"SMB_INA230_3_3V3AUX_SCL_R";
73"SMB_INA230_3_3V3AUX_SDA_R";
74"SMB_INA230_5_3V3AUX_SDA_R";
75"SMB_INA230_4_3V3AUX_SCL_R";
76"SMB_INA230_4_3V3AUX_SDA_R";
77"SMB_INA230_5_3V3AUX_SCL_R";
%"Q_RES"
"2","(525,350)","0","pure_quanta","I100";
;
PART_NUMBER"CS00002JB13"
WATTAGE"1/16W"
VALUE"0"
MATERIAL"CHIP"
PACK_TYPE"0402LF"
TOLERANCE"5%"
$LOCATION"R3620"
CDS_LIB"pure_quanta"
CDS_LOCATION"R3620"
$SEC"1"
CDS_SEC"1";
"A"
$PN"1"70;
"B"
$PN"2"69;
%"Q_RES"
"1","(100,125)","0","pure_quanta","I101";
;
PART_NUMBER"CS03322FB03"
TOLERANCE"1%"
MATERIAL"CHIP"
WATTAGE"1/16W"
PACK_TYPE"0402LF"
VALUE"33.2"
$LOCATION"R3568"
CDS_LIB"pure_quanta"
CDS_LOCATION"R3568"
$SEC"1"
CDS_SEC"1";
"B"
$PN"2"69;
"A"
$PN"1"72;
%"Q_RES"
"1","(100,75)","0","pure_quanta","I102";
;
PART_NUMBER"CS03322FB03"
MATERIAL"CHIP"
TOLERANCE"1%"
VALUE"33.2"
$LOCATION"R3569"
WATTAGE"1/16W"
PACK_TYPE"0402LF"
CDS_LIB"pure_quanta"
CDS_LOCATION"R3569"
$SEC"1"
CDS_SEC"1";
"B"
$PN"2"68;
"A"
$PN"1"73;
%"Q_RES"
"1","(-525,600)","0","pure_quanta","I103";
;
PART_NUMBER"CS24702FB06"
TOLERANCE"1%"
VALUE"4.7K"
WATTAGE"1/16W"
PACK_TYPE"0402LF"
MATERIAL"CHIP"
$LOCATION"R3608"
CDS_LIB"pure_quanta"
CDS_LOCATION"R3608"
$SEC"1"
CDS_SEC"1";
"B"
$PN"2"71;
"A"
$PN"1"22;
%"Q_RES"
"1","(-525,525)","0","pure_quanta","I104";
;
PART_NUMBER"CS24702FB06"
PACK_TYPE"0402LF"
TOLERANCE"1%"
MATERIAL"EMPTY"
VALUE"4.7K"
WATTAGE"1/16W"
$LOCATION"R3609"
CDS_LIB"pure_quanta"
CDS_LOCATION"R3609"
$SEC"1"
CDS_SEC"1";
"B"
$PN"2"70;
"A"
$PN"1"22;
%"UNIVERSAL_GND"
"1","(-950,400)","0","logical_power","I105";
;
HDL_POWER"GND"
CDS_LIB"logical_power";
"A"22;
%"UNIVERSAL_GND"
"1","(2250,-525)","0","logical_power","I107";
;
CDS_LIB"logical_power"
HDL_POWER"GND";
"A"20;
%"Q_CAP"
"1","(500,-625)","0","pure_quanta","I108";
;
PART_NUMBER"CH4104K1B00"
VOLTAGE"25V"
TOLERANCE"10%"
MATERIAL"X7R"
PACK_TYPE"0402"
VALUE"0.1UF"
$LOCATION"C2020"
CDS_LIB"pure_quanta"
CDS_LOCATION"C2020"
$SEC"1"
CDS_SEC"1";
"B"
$PN"2"32;
"A"
$PN"1"33;
%"Q_RES"
"1","(150,-475)","0","pure_quanta","I109";
;
PART_NUMBER"CS01002FB07"
WATTAGE"1/16W"
VALUE"10"
TOLERANCE"1%"
MATERIAL"CHIP"
PACK_TYPE"0402LF"
$LOCATION"R3570"
CDS_LIB"pure_quanta"
CDS_LOCATION"R3570"
$SEC"1"
CDS_SEC"1";
"B"
$PN"2"33;
"A"
$PN"1"17;
%"Q_RES"
"1","(150,-750)","0","pure_quanta","I110";
;
PART_NUMBER"CS01002FB07"
WATTAGE"1/16W"
VALUE"10"
PACK_TYPE"0402LF"
TOLERANCE"1%"
MATERIAL"CHIP"
$LOCATION"R3571"
CDS_LIB"pure_quanta"
CDS_LOCATION"R3571"
$SEC"1"
CDS_SEC"1";
"B"
$PN"2"32;
"A"
$PN"1"11;
%"UNIVERSAL_POWER"
"1","(-1250,-125)","0","logical_power","I112";
;
HDL_POWER"P3V3_OCP_V3_2_R"
CDS_LIB"logical_power";
"A"17;
%"UNIVERSAL_POWER"
"1","(-1400,625)","0","logical_power","I113";
;
HDL_POWER"P3V3_OCP_V3_2_R"
CDS_LIB"logical_power";
"A"10;
%"Q_CAP"
"1","(-1650,300)","0","pure_quanta","I114";
;
PART_NUMBER"CH4104K1B00"
MATERIAL"X7R"
PACK_TYPE"0402"
TOLERANCE"10%"
VOLTAGE"25V"
VALUE"0.1UF"
$LOCATION"C2017"
CDS_LIB"pure_quanta"
CDS_LOCATION"C2017"
$SEC"1"
CDS_SEC"1";
"B"
$PN"2"23;
"A"
$PN"1"10;
%"UNIVERSAL_GND"
"1","(-1650,25)","0","logical_power","I115";
;
CDS_LIB"logical_power"
HDL_POWER"GND";
"A"23;
%"UNIVERSAL_POWER"
"1","(-2325,-125)","0","logical_power","I117";
;
HDL_POWER"P3V3_OCP_V3_2"
CDS_LIB"logical_power";
"A"11;
%"UNIVERSAL_POWER"
"1","(-2625,-4375)","0","logical_power","I118";
;
HDL_POWER"P12V_SCM"
CDS_LIB"logical_power";
"A"16;
%"UNIVERSAL_POWER"
"1","(-1550,-4375)","0","logical_power","I119";
;
HDL_POWER"P12V_SCM_R"
CDS_LIB"logical_power";
"A"5;
%"UNIVERSAL_POWER"
"1","(-1700,-3625)","0","logical_power","I120";
;
HDL_POWER"P12V_SCM_R"
CDS_LIB"logical_power";
"A"15;
%"UNIVERSAL_POWER"
"1","(2575,-3225)","0","logical_power","I121";
;
HDL_POWER"P3V3_AUX"
CDS_LIB"logical_power";
"A"1;
%"Q_RES"
"2","(2575,-3425)","0","pure_quanta","I122";
;
PART_NUMBER"CS24702FB06"
VALUE"4.7K"
TOLERANCE"1%"
MATERIAL"CHIP"
PACK_TYPE"0402LF"
WATTAGE"1/16W"
$LOCATION"R4091"
CDS_LIB"pure_quanta"
CDS_LOCATION"R4091"
$SEC"1"
CDS_SEC"1";
"A"
$PN"1"1;
"B"
$PN"2"44;
%"UNIVERSAL_POWER"
"1","(2500,-1075)","0","logical_power","I123";
;
HDL_POWER"P3V3_AUX"
CDS_LIB"logical_power";
"A"2;
%"Q_RES"
"2","(2500,-1275)","0","pure_quanta","I124";
;
PART_NUMBER"CS24702FB06"
PACK_TYPE"0402LF"
VALUE"4.7K"
TOLERANCE"1%"
WATTAGE"1/16W"
MATERIAL"CHIP"
$LOCATION"R4090"
CDS_LIB"pure_quanta"
CDS_LOCATION"R4090"
$SEC"1"
CDS_SEC"1";
"A"
$PN"1"2;
"B"
$PN"2"31;
%"UNIVERSAL_POWER"
"1","(3075,1025)","0","logical_power","I125";
;
HDL_POWER"P3V3_AUX"
CDS_LIB"logical_power";
"A"3;
%"Q_RES"
"2","(3075,825)","0","pure_quanta","I126";
;
PART_NUMBER"CS24702FB06"
TOLERANCE"1%"
VALUE"4.7K"
PACK_TYPE"0402LF"
WATTAGE"1/16W"
MATERIAL"CHIP"
$LOCATION"R4092"
CDS_LIB"pure_quanta"
CDS_LOCATION"R4092"
$SEC"1"
CDS_SEC"1";
"A"
$PN"1"3;
"B"
$PN"2"41;
%"Q_RES"
"1","(-1750,-275)","0","pure_quanta","I127";
;
PART_NUMBER"CS+0108F128"
MATERIAL"CHIP"
TOLERANCE"1%"
VALUE"0.01"
WATTAGE"1W"
PACK_TYPE"2512LF"
LOCATION"R3633"
CDS_LIB"pure_quanta"
$SEC"1"
CDS_SEC"1";
"B"
$PN"2"17;
"A"
$PN"1"11;
%"Q_RES"
"1","(-2150,-2375)","0","pure_quanta","I128";
;
PART_NUMBER"CS+0108F128"
WATTAGE"1W"
VALUE"0.01"
TOLERANCE"1%"
MATERIAL"CHIP"
PACK_TYPE"2512LF"
LOCATION"R3634"
CDS_LIB"pure_quanta"
$SEC"1"
CDS_SEC"1";
"B"
$PN"2"9;
"A"
$PN"1"7;
%"Q_RES"
"1","(-2050,-4525)","0","pure_quanta","I129";
;
PART_NUMBER"CS+0108F128"
TOLERANCE"1%"
MATERIAL"CHIP"
PACK_TYPE"2512LF"
WATTAGE"1W"
VALUE"0.01"
LOCATION"R3635"
CDS_LIB"pure_quanta"
$SEC"1"
CDS_SEC"1";
"B"
$PN"2"5;
"A"
$PN"1"16;
%"UNIVERSAL_POWER"
"1","(-2750,-2225)","0","logical_power","I24";
;
HDL_POWER"P3V3_M2_0"
CDS_LIB"logical_power";
"A"7;
%"Q_CAP"
"1","(-2075,-1800)","0","pure_quanta","I26";
;
PART_NUMBER"CH4104K1B00"
PACK_TYPE"0402"
TOLERANCE"10%"
VOLTAGE"25V"
VALUE"0.1UF"
MATERIAL"X7R"
$LOCATION"C2018"
CDS_LIB"pure_quanta"
CDS_LOCATION"C2018"
$SEC"1"
CDS_SEC"1";
"B"
$PN"2"24;
"A"
$PN"1"8;
%"UNIVERSAL_GND"
"1","(-2075,-2075)","0","logical_power","I27";
;
HDL_POWER"GND"
CDS_LIB"logical_power";
"A"24;
%"UNIVERSAL_GND"
"1","(-1475,-1875)","0","logical_power","I31";
;
CDS_LIB"logical_power"
HDL_POWER"GND";
"A"25;
%"UNIVERSAL_POWER"
"1","(-1825,-1475)","0","logical_power","I32";
;
HDL_POWER"P3V3"
CDS_LIB"logical_power";
"A"8;
%"Q_RES"
"1","(-275,-2850)","0","pure_quanta","I33";
;
PART_NUMBER"CS01002FB07"
PACK_TYPE"0402LF"
VALUE"10"
TOLERANCE"1%"
MATERIAL"CHIP"
WATTAGE"1/16W"
$LOCATION"R3575"
CDS_LIB"pure_quanta"
CDS_LOCATION"R3575"
$SEC"1"
CDS_SEC"1";
"B"
$PN"2"66;
"A"
$PN"1"7;
%"Q_RES"
"1","(-275,-2575)","0","pure_quanta","I35";
;
PART_NUMBER"CS01002FB07"
TOLERANCE"1%"
WATTAGE"1/16W"
PACK_TYPE"0402LF"
VALUE"10"
MATERIAL"CHIP"
$LOCATION"R3574"
CDS_LIB"pure_quanta"
CDS_LOCATION"R3574"
$SEC"1"
CDS_SEC"1";
"B"
$PN"2"65;
"A"
$PN"1"9;
%"Q_RES"
"1","(-1050,-1750)","0","pure_quanta","I36";
;
PART_NUMBER"CS24702FB06"
WATTAGE"1/16W"
VALUE"4.7K"
TOLERANCE"1%"
MATERIAL"CHIP"
PACK_TYPE"0402LF"
$LOCATION"R3611"
CDS_LIB"pure_quanta"
CDS_LOCATION"R3611"
$SEC"1"
CDS_SEC"1";
"B"
$PN"2"62;
"A"
$PN"1"25;
%"Q_RES"
"1","(-300,-2025)","0","pure_quanta","I37";
;
PART_NUMBER"CS03322FB03"
MATERIAL"CHIP"
TOLERANCE"1%"
VALUE"33.2"
$LOCATION"R3573"
WATTAGE"1/16W"
PACK_TYPE"0402LF"
CDS_LIB"pure_quanta"
CDS_LOCATION"R3573"
$SEC"1"
CDS_SEC"1";
"B"
$PN"2"64;
"A"
$PN"1"76;
%"Q_RES"
"1","(-300,-1975)","0","pure_quanta","I38";
;
PART_NUMBER"CS03322FB03"
WATTAGE"1/16W"
MATERIAL"CHIP"
TOLERANCE"1%"
PACK_TYPE"0402LF"
VALUE"33.2"
$LOCATION"R3572"
CDS_LIB"pure_quanta"
CDS_LOCATION"R3572"
$SEC"1"
CDS_SEC"1";
"B"
$PN"2"63;
"A"
$PN"1"75;
%"UNIVERSAL_GND"
"1","(600,-1650)","0","logical_power","I39";
;
CDS_LIB"logical_power"
HDL_POWER"GND";
"A"26;
%"UNIVERSAL_GND"
"1","(1825,-2625)","0","logical_power","I40";
;
HDL_POWER"GND"
CDS_LIB"logical_power";
"A"19;
%"Q_RES"
"1","(2700,-1725)","0","pure_quanta","I41";
;
PART_NUMBER"CS00002JB13"
VALUE"0"
PACK_TYPE"0402LF"
MATERIAL"CHIP"
$LOCATION"R3560"
WATTAGE"1/16W"
TOLERANCE"5%"
CDS_LIB"pure_quanta"
CDS_LOCATION"R3560"
$SEC"1"
CDS_SEC"1";
"B"
$PN"2"58;
"A"
$PN"1"31;
%"Q_CAP"
"1","(600,-1375)","0","pure_quanta","I42";
;
PART_NUMBER"CH4104K1B00"
VALUE"0.1UF"
PACK_TYPE"0402"
TOLERANCE"10%"
MATERIAL"X7R"
VOLTAGE"25V"
$LOCATION"C2013"
CDS_LIB"pure_quanta"
CDS_LOCATION"C2013"
$SEC"1"
CDS_SEC"1";
"B"
$PN"2"26;
"A"
$PN"1"12;
%"UNIVERSAL_POWER"
"1","(850,-975)","0","logical_power","I43";
;
HDL_POWER"P3V3_AUX"
CDS_LIB"logical_power";
"A"12;
%"Q_RES"
"1","(-1050,-1675)","0","pure_quanta","I45";
;
PART_NUMBER"CS24702FB06"
WATTAGE"1/16W"
PACK_TYPE"0402LF"
MATERIAL"EMPTY"
TOLERANCE"1%"
VALUE"4.7K"
$LOCATION"R3610"
CDS_LIB"pure_quanta"
CDS_LOCATION"R3610"
$SEC"1"
CDS_SEC"1";
"B"
$PN"2"34;
"A"
$PN"1"25;
%"INA230AIRGTR"
"1","(1300,-1975)","0","pure_quanta","I46";
;
PART_NUMBER"AL000230001"
VALUE"INA230AIRGTR"
MATERIAL"IC"
PART_TYPE"SMLF"
$LOCATION"U264"
NEEDS_NO_SIZE"TRUE"
CDS_LMAN_SYM_OUTLINE"-250,300,250,-300"
CDS_LIB"pure_quanta"
CDS_LOCATION"U264"
$SEC"1"
CDS_SEC"1";
"TH"
$PN"TH"19;
"GND"
$PN"10"19;
"NC5"
$PN"16"61;
"NC4"
$PN"15"43;
"NC3"
$PN"14"42;
"NC2"
$PN"8"60;
"NC1"
$PN"7"59;
"NC0"
$PN"6"30;
"ALERT"
$PN"3"31;
"IN-"
$PN"12"66;
"IN+"
$PN"13"65;
"BUS"
$PN"11"8;
"SDA"
$PN"4"64;
"SCL"
$PN"5"63;
"A0"
$PN"2"62;
"A1"
$PN"1"34;
"VS"
$PN"9"12;
%"Q_CAP"
"1","(-1950,-3950)","0","pure_quanta","I49";
;
PART_NUMBER"CH4104K1B00"
VOLTAGE"25V"
MATERIAL"X7R"
VALUE"0.1UF"
PACK_TYPE"0402"
TOLERANCE"10%"
$LOCATION"C2019"
CDS_LIB"pure_quanta"
CDS_LOCATION"C2019"
$SEC"1"
CDS_SEC"1";
"B"
$PN"2"27;
"A"
$PN"1"15;
%"UNIVERSAL_GND"
"1","(-1950,-4225)","0","logical_power","I50";
;
CDS_LIB"logical_power"
HDL_POWER"GND";
"A"27;
%"UNIVERSAL_GND"
"1","(-1400,-4050)","0","logical_power","I54";
;
CDS_LIB"logical_power"
HDL_POWER"GND";
"A"28;
%"Q_RES"
"1","(-150,-5000)","0","pure_quanta","I56";
;
PART_NUMBER"CS01002FB07"
MATERIAL"CHIP"
PACK_TYPE"0402LF"
VALUE"10"
TOLERANCE"1%"
WATTAGE"1/16W"
$LOCATION"R3579"
CDS_LIB"pure_quanta"
CDS_LOCATION"R3579"
$SEC"1"
CDS_SEC"1";
"B"
$PN"2"57;
"A"
$PN"1"16;
%"Q_RES"
"1","(-150,-4725)","0","pure_quanta","I58";
;
PART_NUMBER"CS01002FB07"
PACK_TYPE"0402LF"
VALUE"10"
TOLERANCE"1%"
MATERIAL"CHIP"
WATTAGE"1/16W"
$LOCATION"R3578"
CDS_LIB"pure_quanta"
CDS_LOCATION"R3578"
$SEC"1"
CDS_SEC"1";
"B"
$PN"2"56;
"A"
$PN"1"5;
%"Q_RES"
"1","(-975,-3925)","0","pure_quanta","I59";
;
PART_NUMBER"CS24702FB06"
VALUE"4.7K"
TOLERANCE"1%"
WATTAGE"1/16W"
PACK_TYPE"0402LF"
MATERIAL"EMPTY"
$LOCATION"R3613"
CDS_LIB"pure_quanta"
CDS_LOCATION"R3613"
$SEC"1"
CDS_SEC"1";
"B"
$PN"2"53;
"A"
$PN"1"28;
%"Q_RES"
"1","(-175,-4175)","0","pure_quanta","I60";
;
PART_NUMBER"CS03322FB03"
MATERIAL"CHIP"
TOLERANCE"1%"
VALUE"33.2"
$LOCATION"R3577"
CDS_LIB"pure_quanta"
PACK_TYPE"0402LF"
WATTAGE"1/16W"
CDS_LOCATION"R3577"
$SEC"1"
CDS_SEC"1";
"B"
$PN"2"55;
"A"
$PN"1"74;
%"Q_RES"
"1","(-175,-4125)","0","pure_quanta","I61";
;
PART_NUMBER"CS03322FB03"
MATERIAL"CHIP"
TOLERANCE"1%"
WATTAGE"1/16W"
PACK_TYPE"0402LF"
VALUE"33.2"
$LOCATION"R3576"
CDS_LIB"pure_quanta"
CDS_LOCATION"R3576"
$SEC"1"
CDS_SEC"1";
"B"
$PN"2"54;
"A"
$PN"1"77;
%"UNIVERSAL_GND"
"1","(725,-3800)","0","logical_power","I62";
;
HDL_POWER"GND"
CDS_LIB"logical_power";
"A"29;
%"UNIVERSAL_GND"
"1","(1950,-4775)","0","logical_power","I63";
;
CDS_LIB"logical_power"
HDL_POWER"GND";
"A"18;
%"Q_RES"
"1","(2825,-3875)","0","pure_quanta","I64";
;
PART_NUMBER"CS00002JB13"
PACK_TYPE"0402LF"
VALUE"0"
MATERIAL"CHIP"
$LOCATION"R3561"
CDS_LIB"pure_quanta"
TOLERANCE"5%"
WATTAGE"1/16W"
CDS_LOCATION"R3561"
$SEC"1"
CDS_SEC"1";
"B"
$PN"2"46;
"A"
$PN"1"44;
%"Q_CAP"
"1","(725,-3525)","0","pure_quanta","I65";
;
PART_NUMBER"CH4104K1B00"
MATERIAL"X7R"
PACK_TYPE"0402"
VALUE"0.1UF"
VOLTAGE"25V"
TOLERANCE"10%"
$LOCATION"C2014"
CDS_LIB"pure_quanta"
CDS_LOCATION"C2014"
$SEC"1"
CDS_SEC"1";
"B"
$PN"2"29;
"A"
$PN"1"14;
%"UNIVERSAL_POWER"
"1","(975,-3125)","0","logical_power","I66";
;
HDL_POWER"P3V3_AUX"
CDS_LIB"logical_power";
"A"14;
%"Q_RES"
"1","(-975,-3850)","0","pure_quanta","I68";
;
PART_NUMBER"CS24702FB06"
PACK_TYPE"0402LF"
WATTAGE"1/16W"
VALUE"4.7K"
TOLERANCE"1%"
MATERIAL"EMPTY"
$LOCATION"R3612"
CDS_LIB"pure_quanta"
CDS_LOCATION"R3612"
$SEC"1"
CDS_SEC"1";
"B"
$PN"2"52;
"A"
$PN"1"28;
%"INA230AIRGTR"
"1","(1425,-4125)","0","pure_quanta","I69";
;
PART_NUMBER"AL000230001"
PART_TYPE"SMLF"
MATERIAL"IC"
VALUE"INA230AIRGTR"
$LOCATION"U265"
CDS_LIB"pure_quanta"
CDS_LMAN_SYM_OUTLINE"-250,300,250,-300"
NEEDS_NO_SIZE"TRUE"
CDS_LOCATION"U265"
$SEC"1"
CDS_SEC"1";
"TH"
$PN"TH"18;
"GND"
$PN"10"18;
"NC5"
$PN"16"50;
"NC4"
$PN"15"49;
"NC3"
$PN"14"51;
"NC2"
$PN"8"45;
"NC1"
$PN"7"47;
"NC0"
$PN"6"48;
"ALERT"
$PN"3"44;
"IN-"
$PN"12"57;
"IN+"
$PN"13"56;
"BUS"
$PN"11"15;
"SDA"
$PN"4"55;
"SCL"
$PN"5"54;
"A0"
$PN"2"53;
"A1"
$PN"1"52;
"VS"
$PN"9"14;
%"Q_CAP"
"1","(75,-2725)","0","pure_quanta","I71";
;
PART_NUMBER"CH4104K1B00"
TOLERANCE"10%"
MATERIAL"X7R"
VOLTAGE"25V"
VALUE"0.1UF"
PACK_TYPE"0402"
$LOCATION"C2021"
CDS_LIB"pure_quanta"
CDS_LOCATION"C2021"
$SEC"1"
CDS_SEC"1";
"B"
$PN"2"66;
"A"
$PN"1"65;
%"Q_CAP"
"1","(200,-4875)","0","pure_quanta","I72";
;
PART_NUMBER"CH4104K1B00"
VALUE"0.1UF"
VOLTAGE"25V"
TOLERANCE"10%"
MATERIAL"X7R"
PACK_TYPE"0402"
$LOCATION"C2022"
CDS_LIB"pure_quanta"
CDS_LOCATION"C2022"
$SEC"1"
CDS_SEC"1";
"B"
$PN"2"57;
"A"
$PN"1"56;
%"UNIVERSAL_POWER"
"1","(-1675,-2225)","0","logical_power","I76";
;
HDL_POWER"P3V3"
CDS_LIB"logical_power";
"A"9;
%"UNIVERSAL_POWER"
"1","(75,-1025)","0","logical_power","I85";
;
HDL_POWER"P3V3_AUX"
CDS_LIB"logical_power";
"A"6;
%"Q_RES"
"2","(75,-1325)","0","pure_quanta","I86";
;
PART_NUMBER"CS24702FB06"
WATTAGE"1/16W"
VALUE"4.7K"
TOLERANCE"1%"
PACK_TYPE"0402LF"
MATERIAL"CHIP"
$LOCATION"R3623"
CDS_LIB"pure_quanta"
CDS_LOCATION"R3623"
$SEC"1"
CDS_SEC"1";
"A"
$PN"1"6;
"B"
$PN"2"34;
%"Q_RES"
"2","(-225,-1325)","0","pure_quanta","I87";
;
PART_NUMBER"CS24702FB06"
VALUE"4.7K"
TOLERANCE"1%"
PACK_TYPE"0402LF"
WATTAGE"1/16W"
MATERIAL"EMPTY"
$LOCATION"R3621"
CDS_LIB"pure_quanta"
CDS_LOCATION"R3621"
$SEC"1"
CDS_SEC"1";
"A"
$PN"1"6;
"B"
$PN"2"62;
%"UNIVERSAL_POWER"
"1","(125,-3225)","0","logical_power","I88";
;
HDL_POWER"P3V3_AUX"
CDS_LIB"logical_power";
"A"13;
%"Q_RES"
"2","(125,-3525)","0","pure_quanta","I89";
;
PART_NUMBER"CS24702FB06"
TOLERANCE"1%"
VALUE"4.7K"
MATERIAL"CHIP"
PACK_TYPE"0402LF"
WATTAGE"1/16W"
$LOCATION"R3624"
CDS_LIB"pure_quanta"
CDS_LOCATION"R3624"
$SEC"1"
CDS_SEC"1";
"A"
$PN"1"13;
"B"
$PN"2"52;
%"Q_RES"
"2","(-175,-3525)","0","pure_quanta","I90";
;
PART_NUMBER"CS24702FB06"
MATERIAL"CHIP"
VALUE"4.7K"
PACK_TYPE"0402LF"
TOLERANCE"1%"
WATTAGE"1/16W"
$LOCATION"R3622"
CDS_LIB"pure_quanta"
CDS_LOCATION"R3622"
$SEC"1"
CDS_SEC"1";
"A"
$PN"1"13;
"B"
$PN"2"53;
%"INA230AIRGTR"
"1","(1725,125)","0","pure_quanta","I94";
;
PART_NUMBER"AL000230001"
VALUE"INA230AIRGTR"
MATERIAL"IC"
PART_TYPE"SMLF"
$LOCATION"U263"
NEEDS_NO_SIZE"TRUE"
CDS_LMAN_SYM_OUTLINE"-250,300,250,-300"
CDS_LIB"pure_quanta"
CDS_LOCATION"U263"
$SEC"1"
CDS_SEC"1";
"TH"
$PN"TH"20;
"GND"
$PN"10"20;
"NC5"
$PN"16"35;
"NC4"
$PN"15"36;
"NC3"
$PN"14"37;
"NC2"
$PN"8"38;
"NC1"
$PN"7"39;
"NC0"
$PN"6"40;
"ALERT"
$PN"3"41;
"IN-"
$PN"12"32;
"IN+"
$PN"13"33;
"BUS"
$PN"11"10;
"SDA"
$PN"4"68;
"SCL"
$PN"5"69;
"A0"
$PN"2"70;
"A1"
$PN"1"71;
"VS"
$PN"9"4;
%"Q_RES"
"1","(3275,375)","0","pure_quanta","I96";
;
PART_NUMBER"CS00002JB13"
PACK_TYPE"0402LF"
VALUE"0"
MATERIAL"CHIP"
$LOCATION"R3559"
WATTAGE"1/16W"
TOLERANCE"5%"
CDS_LIB"pure_quanta"
CDS_LOCATION"R3559"
$SEC"1"
CDS_SEC"1";
"B"
$PN"2"67;
"A"
$PN"1"41;
%"UNIVERSAL_POWER"
"1","(1275,1125)","0","logical_power","I97";
;
HDL_POWER"P3V3_AUX"
CDS_LIB"logical_power";
"A"4;
%"Q_CAP"
"1","(1025,725)","0","pure_quanta","I98";
;
PART_NUMBER"CH4104K1B00"
MATERIAL"X7R"
TOLERANCE"10%"
VOLTAGE"25V"
VALUE"0.1UF"
PACK_TYPE"0402"
$LOCATION"C2012"
CDS_LIB"pure_quanta"
CDS_LOCATION"C2012"
$SEC"1"
CDS_SEC"1";
"B"
$PN"2"21;
"A"
$PN"1"4;
%"UNIVERSAL_GND"
"1","(1025,450)","0","logical_power","I99";
;
HDL_POWER"GND"
CDS_LIB"logical_power";
"A"21;
END.
